# T6G (Grand Teton) — schematic netlist excerpt (pin names and nets, part order shuffled) for the footprints in the layout excerpt that follows; sources: Cadence DE-HDL packaged netlist, KiCad conversion of 04192023_DAF0TMB3IC0_F0TG_MB_C_brd_V02_OCP.brd

C548  Q_CAP  10UF 25V 10% X6S  pkg C0805  page 109 : A = P12V_MEM_CPU1 ; B = GND
R3940  Q_RES  0 5% EMPTY  pkg 0402LF  page 257 : A = P12V_E1S_0_ISENSE_MPS_MAM ; B = P12V_E1S_0_ISENSE_MAM
C2522  Q_CAP  22UF 4V 20% X6S  pkg C0402  page 71 : A = PVDD18_S5_P0 ; B = GND

(kicad_pcb
	(version 20260206)
	(generator "pcbnew")
	(generator_version "10.0")
	(general
		(thickness 1.6)
		(legacy_teardrops no)
	)
	(paper "A4")
	(title_block
		(title "04192023_DAF0TMB3IC0_F0TG_MB_C_brd_V02_OCP.brd")
		(comment 1 "Grand Teton / footprints 8314-8316 of 8354")
	)
	(layers
		(0 "F.Cu" signal "TOP")
		(4 "In1.Cu" signal "GND")
		(6 "In2.Cu" signal "IN1")
		(8 "In3.Cu" signal "GND1")
		(10 "In4.Cu" signal "IN2")
		(12 "In5.Cu" signal "GND2")
		(14 "In6.Cu" signal "IN3")
		(16 "In7.Cu" signal "GND3")
		(18 "In8.Cu" signal "VCC")
		(20 "In9.Cu" signal "VCC1")
		(22 "In10.Cu" signal "GND4")
		(24 "In11.Cu" signal "IN4")
		(26 "In12.Cu" signal "GND5")
		(28 "In13.Cu" signal "IN5")
		(30 "In14.Cu" signal "GND6")
		(32 "In15.Cu" signal "IN6")
		(34 "In16.Cu" signal "GND7")
		(2 "B.Cu" signal "BOTTOM")
		(9 "F.Adhes" user "F.Adhesive")
		(11 "B.Adhes" user "B.Adhesive")
		(13 "F.Paste" user "Package Geometry/Pastemask Top")
		(15 "B.Paste" user "Package Geometry/Pastemask Bottom")
		(5 "F.SilkS" user "Ref Des/Silkscreen Top")
		(7 "B.SilkS" user "Ref Des/Silkscreen Bottom")
		(1 "F.Mask" user "Board Geometry/Soldermask Top")
		(3 "B.Mask" user "Board Geometry/Soldermask Bottom")
		(17 "Dwgs.User" user "User.Drawings")
		(19 "Cmts.User" user "User.Comments")
		(21 "Eco1.User" user "User.Eco1")
		(23 "Eco2.User" user "User.Eco2")
		(25 "Edge.Cuts" user "Board Geometry/Outline")
		(27 "Margin" user)
		(31 "F.CrtYd" user "Package Geometry/Place Bound Top")
		(29 "B.CrtYd" user "Package Geometry/Place Bound Bottom")
		(35 "F.Fab" user "Ref Des/Assembly Top")
		(33 "B.Fab" user "Ref Des/Assembly Bottom")
	)
	(footprint ""
		(layer "B.Cu")
		(at 348.888558 -254.06731 180)
		(property "Reference" "C2522"
			(at 0 0 0)
			(layer "B.SilkS")
			(hide yes)
			(effects
				(font
					(size 1.27 1.27)
				)
				(justify mirror)
			)
		)
		(property "Value" ""
			(at 0 0 0)
			(layer "B.Fab")
			(effects
				(font
					(size 1.27 1.27)
				)
				(justify mirror)
			)
		)
		(duplicate_pad_numbers_are_jumpers no)
		(fp_line
			(start 0.7874 0.4064)
			(end 0.7874 -0.4064)
			(stroke
				(width 0.1524)
				(type default)
			)
			(layer "B.SilkS")
		)
		(fp_line
			(start 0.7874 -0.4064)
			(end -0.7874 -0.4064)
			(stroke
				(width 0.1524)
				(type default)
			)
			(layer "B.SilkS")
		)
		(fp_line
			(start -0.7874 0.4064)
			(end 0.7874 0.4064)
			(stroke
				(width 0.1524)
				(type default)
			)
			(layer "B.SilkS")
		)
		(fp_line
			(start -0.7874 -0.4064)
			(end -0.7874 0.4064)
			(stroke
				(width 0.1524)
				(type default)
			)
			(layer "B.SilkS")
		)
		(fp_line
			(start 0.67945 0.3048)
			(end 0.67945 -0.305054)
			(stroke
				(width 0.1)
				(type default)
			)
			(layer "B.Fab")
		)
		(fp_line
			(start 0.67945 -0.305054)
			(end 0.12065 -0.305054)
			(stroke
				(width 0.1)
				(type default)
			)
			(layer "B.Fab")
		)
		(fp_line
			(start 0.12065 0.3048)
			(end 0.67945 0.3048)
			(stroke
				(width 0.1)
				(type default)
			)
			(layer "B.Fab")
		)
		(fp_line
			(start 0.12065 0.2794)
			(end 0.12065 0.3048)
			(stroke
				(width 0.1)
				(type default)
			)
			(layer "B.Fab")
		)
		(fp_line
			(start 0.12065 -0.2794)
			(end -0.12065 -0.2794)
			(stroke
				(width 0.1)
				(type default)
			)
			(layer "B.Fab")
		)
		(fp_line
			(start 0.12065 -0.305054)
			(end 0.12065 -0.2794)
			(stroke
				(width 0.1)
				(type default)
			)
			(layer "B.Fab")
		)
		(fp_line
			(start -0.120396 0.3048)
			(end -0.120396 0.2794)
			(stroke
				(width 0.1)
				(type default)
			)
			(layer "B.Fab")
		)
		(fp_line
			(start -0.120396 0.2794)
			(end 0.12065 0.2794)
			(stroke
				(width 0.1)
				(type default)
			)
			(layer "B.Fab")
		)
		(fp_line
			(start -0.12065 -0.2794)
			(end -0.12065 -0.3048)
			(stroke
				(width 0.1)
				(type default)
			)
			(layer "B.Fab")
		)
		(fp_line
			(start -0.12065 -0.3048)
			(end -0.67945 -0.3048)
			(stroke
				(width 0.1)
				(type default)
			)
			(layer "B.Fab")
		)
		(fp_line
			(start -0.67945 0.3048)
			(end -0.120396 0.3048)
			(stroke
				(width 0.1)
				(type default)
			)
			(layer "B.Fab")
		)
		(fp_line
			(start -0.67945 -0.3048)
			(end -0.67945 0.3048)
			(stroke
				(width 0.1)
				(type default)
			)
			(layer "B.Fab")
		)
		(pad "1" smd circle
			(at 0.40005 0)
			(size 0 0)
			(layers "B.Cu" "B.Mask" "B.Paste")
			(net "PVDD18_S5_P0")
		)
		(pad "2" smd circle
			(at -0.40005 0)
			(size 0 0)
			(layers "B.Cu" "B.Mask" "B.Paste")
			(net "GND")
		)
	)
	(footprint ""
		(layer "B.Cu")
		(at 325.635112 -33.851342 -90)
		(property "Reference" "R3940"
			(at 0 0 90)
			(layer "B.SilkS")
			(hide yes)
			(effects
				(font
					(size 1.27 1.27)
				)
				(justify mirror)
			)
		)
		(property "Value" ""
			(at 0 0 90)
			(layer "B.Fab")
			(effects
				(font
					(size 1.27 1.27)
				)
				(justify mirror)
			)
		)
		(duplicate_pad_numbers_are_jumpers no)
		(fp_line
			(start -0.7874 0.4064)
			(end 0.7874 0.4064)
			(stroke
				(width 0.1524)
				(type default)
			)
			(layer "B.SilkS")
		)
		(fp_line
			(start 0.7874 0.4064)
			(end 0.7874 -0.4064)
			(stroke
				(width 0.1524)
				(type default)
			)
			(layer "B.SilkS")
		)
		(fp_line
			(start -0.7874 -0.4064)
			(end -0.7874 0.4064)
			(stroke
				(width 0.1524)
				(type default)
			)
			(layer "B.SilkS")
		)
		(fp_line
			(start 0.7874 -0.4064)
			(end -0.7874 -0.4064)
			(stroke
				(width 0.1524)
				(type default)
			)
			(layer "B.SilkS")
		)
		(fp_line
			(start -0.67945 0.3048)
			(end -0.120396 0.3048)
			(stroke
				(width 0.1)
				(type default)
			)
			(layer "B.Fab")
		)
		(fp_line
			(start -0.120396 0.3048)
			(end -0.120396 0.2794)
			(stroke
				(width 0.1)
				(type default)
			)
			(layer "B.Fab")
		)
		(fp_line
			(start 0.12065 0.3048)
			(end 0.67945 0.3048)
			(stroke
				(width 0.1)
				(type default)
			)
			(layer "B.Fab")
		)
		(fp_line
			(start 0.67945 0.3048)
			(end 0.67945 -0.305054)
			(stroke
				(width 0.1)
				(type default)
			)
			(layer "B.Fab")
		)
		(fp_line
			(start -0.120396 0.2794)
			(end 0.12065 0.2794)
			(stroke
				(width 0.1)
				(type default)
			)
			(layer "B.Fab")
		)
		(fp_line
			(start 0.12065 0.2794)
			(end 0.12065 0.3048)
			(stroke
				(width 0.1)
				(type default)
			)
			(layer "B.Fab")
		)
		(fp_line
			(start -0.12065 -0.2794)
			(end -0.12065 -0.3048)
			(stroke
				(width 0.1)
				(type default)
			)
			(layer "B.Fab")
		)
		(fp_line
			(start 0.12065 -0.2794)
			(end -0.12065 -0.2794)
			(stroke
				(width 0.1)
				(type default)
			)
			(layer "B.Fab")
		)
		(fp_line
			(start -0.67945 -0.3048)
			(end -0.67945 0.3048)
			(stroke
				(width 0.1)
				(type default)
			)
			(layer "B.Fab")
		)
		(fp_line
			(start -0.12065 -0.3048)
			(end -0.67945 -0.3048)
			(stroke
				(width 0.1)
				(type default)
			)
			(layer "B.Fab")
		)
		(fp_line
			(start 0.12065 -0.305054)
			(end 0.12065 -0.2794)
			(stroke
				(width 0.1)
				(type default)
			)
			(layer "B.Fab")
		)
		(fp_line
			(start 0.67945 -0.305054)
			(end 0.12065 -0.305054)
			(stroke
				(width 0.1)
				(type default)
			)
			(layer "B.Fab")
		)
		(pad "1" smd rect
			(at 0.40005 0 270)
			(size 0.4572 0.508)
			(layers "B.Cu" "B.Mask" "B.Paste")
			(net "P12V_E1S_0_ISENSE_MPS_MAM")
		)
		(pad "2" smd rect
			(at -0.40005 0 270)
			(size 0.4572 0.508)
			(layers "B.Cu" "B.Mask" "B.Paste")
			(net "P12V_E1S_0_ISENSE_MAM")
		)
	)
	(footprint ""
		(layer "B.Cu")
		(at 206.248 -192.660016)
		(property "Reference" "C548"
			(at 0 0 0)
			(layer "B.SilkS")
			(hide yes)
			(effects
				(font
					(size 1.27 1.27)
				)
				(justify mirror)
			)
		)
		(property "Value" ""
			(at 0 0 0)
			(layer "B.Fab")
			(effects
				(font
					(size 1.27 1.27)
				)
				(justify mirror)
			)
		)
		(duplicate_pad_numbers_are_jumpers no)
		(fp_line
			(start -1.524 -0.762)
			(end -1.524 0.762)
			(stroke
				(width 0.1524)
				(type default)
			)
			(layer "B.SilkS")
		)
		(fp_line
			(start -1.524 0.762)
			(end 1.524 0.762)
			(stroke
				(width 0.1524)
				(type default)
			)
			(layer "B.SilkS")
		)
		(fp_line
			(start 1.524 -0.762)
			(end -1.524 -0.762)
			(stroke
				(width 0.1524)
				(type default)
			)
			(layer "B.SilkS")
		)
		(fp_line
			(start 1.524 0.762)
			(end 1.524 -0.762)
			(stroke
				(width 0.1524)
				(type default)
			)
			(layer "B.SilkS")
		)
		(fp_line
			(start -1.1049 -0.724916)
			(end 1.1049 -0.724916)
			(stroke
				(width 0.1)
				(type default)
			)
			(layer "B.Fab")
		)
		(fp_line
			(start -1.1049 0.724916)
			(end -1.1049 -0.724916)
			(stroke
				(width 0.1)
				(type default)
			)
			(layer "B.Fab")
		)
		(fp_line
			(start 1.1049 -0.724916)
			(end 1.1049 0.724916)
			(stroke
				(width 0.1)
				(type default)
			)
			(layer "B.Fab")
		)
		(fp_line
			(start 1.1049 0.724916)
			(end -1.1049 0.724916)
			(stroke
				(width 0.1)
				(type default)
			)
			(layer "B.Fab")
		)
		(pad "1" smd rect
			(at 0.889 0)
			(size 1.016 1.27)
			(layers "B.Cu" "B.Mask" "B.Paste")
			(net "P12V_MEM_CPU1")
		)
		(pad "2" smd rect
			(at -0.889 0)
			(size 1.016 1.27)
			(layers "B.Cu" "B.Mask" "B.Paste")
			(net "GND")
		)
	)
)
